# S9S_MB_2U (Grand Teton) — schematic netlist excerpt (pin names and nets, part order shuffled) for the footprints in the layout excerpt that follows; sources: Cadence DE-HDL packaged netlist, KiCad conversion of 03242023_DA0F0TMBIJ0_F0T_Motherboard_J_brd_V01_OCP.brd

C709  Q_CAP_DIFFBUS  DIFF BUS_0.22UF 6.3V 20% X6S  pkg C0201  page 177 : \1\ = P5E_CPU1_PE4_TX_C_DP<0> ; \2\ = P5E_CPU1_PE4_TX_DP<0>
C436  Q_CAP  22UF 4V 20% X6S  pkg C0402  page 77 : A = PVCCINFAON_CPU1 ; B = GND
R3731  Q_RES  2.2K 5% CHIP  pkg 0402LF  page 233 : A = P3V3_AUX ; B = SMB_LM75_3_3V3AUX_SCL

(kicad_pcb
	(version 20260206)
	(generator "pcbnew")
	(generator_version "10.0")
	(general
		(thickness 1.6)
		(legacy_teardrops no)
	)
	(paper "A4")
	(title_block
		(title "03242023_DA0F0TMBIJ0_F0T_Motherboard_J_brd_V01_OCP.brd")
		(comment 1 "Grand Teton / footprints 1125-1127 of 6105")
	)
	(layers
		(0 "F.Cu" signal "TOP")
		(4 "In1.Cu" signal "GND")
		(6 "In2.Cu" signal "IN1")
		(8 "In3.Cu" signal "GND1")
		(10 "In4.Cu" signal "IN2")
		(12 "In5.Cu" signal "GND2")
		(14 "In6.Cu" signal "IN3")
		(16 "In7.Cu" signal "GND3")
		(18 "In8.Cu" signal "VCC")
		(20 "In9.Cu" signal "VCC1")
		(22 "In10.Cu" signal "GND4")
		(24 "In11.Cu" signal "IN4")
		(26 "In12.Cu" signal "GND5")
		(28 "In13.Cu" signal "IN5")
		(30 "In14.Cu" signal "GND6")
		(32 "In15.Cu" signal "IN6")
		(34 "In16.Cu" signal "GND7")
		(2 "B.Cu" signal "BOTTOM")
		(9 "F.Adhes" user "F.Adhesive")
		(11 "B.Adhes" user "B.Adhesive")
		(13 "F.Paste" user "Package Geometry/Pastemask Top")
		(15 "B.Paste" user "Package Geometry/Pastemask Bottom")
		(5 "F.SilkS" user "Ref Des/Silkscreen Top")
		(7 "B.SilkS" user "Ref Des/Silkscreen Bottom")
		(1 "F.Mask" user "Board Geometry/Soldermask Top")
		(3 "B.Mask" user "Board Geometry/Soldermask Bottom")
		(17 "Dwgs.User" user "User.Drawings")
		(19 "Cmts.User" user "User.Comments")
		(21 "Eco1.User" user "User.Eco1")
		(23 "Eco2.User" user "User.Eco2")
		(25 "Edge.Cuts" user "Board Geometry/Outline")
		(27 "Margin" user)
		(31 "F.CrtYd" user "Package Geometry/Place Bound Top")
		(29 "B.CrtYd" user "Package Geometry/Place Bound Bottom")
		(35 "F.Fab" user "Ref Des/Assembly Top")
		(33 "B.Fab" user "Ref Des/Assembly Bottom")
	)
	(footprint ""
		(layer "F.Cu")
		(at 117.526816 -238.162592 90)
		(property "Reference" "C436"
			(at 0 0 90)
			(layer "F.SilkS")
			(hide yes)
			(effects
				(font
					(size 1.27 1.27)
				)
			)
		)
		(property "Value" ""
			(at 0 0 90)
			(layer "F.Fab")
			(effects
				(font
					(size 1.27 1.27)
				)
			)
		)
		(duplicate_pad_numbers_are_jumpers no)
		(fp_line
			(start 0.7874 -0.4064)
			(end 0.7874 0.4064)
			(stroke
				(width 0.1524)
				(type default)
			)
			(layer "F.SilkS")
		)
		(fp_line
			(start -0.7874 -0.4064)
			(end 0.7874 -0.4064)
			(stroke
				(width 0.1524)
				(type default)
			)
			(layer "F.SilkS")
		)
		(fp_line
			(start 0.7874 0.4064)
			(end -0.7874 0.4064)
			(stroke
				(width 0.1524)
				(type default)
			)
			(layer "F.SilkS")
		)
		(fp_line
			(start -0.7874 0.4064)
			(end -0.7874 -0.4064)
			(stroke
				(width 0.1524)
				(type default)
			)
			(layer "F.SilkS")
		)
		(fp_line
			(start -0.12065 -0.305054)
			(end -0.12065 -0.2794)
			(stroke
				(width 0.1)
				(type default)
			)
			(layer "F.Fab")
		)
		(fp_line
			(start -0.67945 -0.305054)
			(end -0.12065 -0.305054)
			(stroke
				(width 0.1)
				(type default)
			)
			(layer "F.Fab")
		)
		(fp_line
			(start 0.67945 -0.3048)
			(end 0.67945 0.3048)
			(stroke
				(width 0.1)
				(type default)
			)
			(layer "F.Fab")
		)
		(fp_line
			(start 0.12065 -0.3048)
			(end 0.67945 -0.3048)
			(stroke
				(width 0.1)
				(type default)
			)
			(layer "F.Fab")
		)
		(fp_line
			(start 0.12065 -0.2794)
			(end 0.12065 -0.3048)
			(stroke
				(width 0.1)
				(type default)
			)
			(layer "F.Fab")
		)
		(fp_line
			(start -0.12065 -0.2794)
			(end 0.12065 -0.2794)
			(stroke
				(width 0.1)
				(type default)
			)
			(layer "F.Fab")
		)
		(fp_line
			(start 0.120396 0.2794)
			(end -0.12065 0.2794)
			(stroke
				(width 0.1)
				(type default)
			)
			(layer "F.Fab")
		)
		(fp_line
			(start -0.12065 0.2794)
			(end -0.12065 0.3048)
			(stroke
				(width 0.1)
				(type default)
			)
			(layer "F.Fab")
		)
		(fp_line
			(start 0.67945 0.3048)
			(end 0.120396 0.3048)
			(stroke
				(width 0.1)
				(type default)
			)
			(layer "F.Fab")
		)
		(fp_line
			(start 0.120396 0.3048)
			(end 0.120396 0.2794)
			(stroke
				(width 0.1)
				(type default)
			)
			(layer "F.Fab")
		)
		(fp_line
			(start -0.12065 0.3048)
			(end -0.67945 0.3048)
			(stroke
				(width 0.1)
				(type default)
			)
			(layer "F.Fab")
		)
		(fp_line
			(start -0.67945 0.3048)
			(end -0.67945 -0.305054)
			(stroke
				(width 0.1)
				(type default)
			)
			(layer "F.Fab")
		)
		(pad "1" smd circle
			(at -0.40005 0 90)
			(size 0 0)
			(layers "F.Cu" "F.Mask" "F.Paste")
			(net "PVCCINFAON_CPU1")
		)
		(pad "2" smd circle
			(at 0.40005 0 90)
			(size 0 0)
			(layers "F.Cu" "F.Mask" "F.Paste")
			(net "GND")
		)
	)
	(footprint ""
		(layer "F.Cu")
		(at 50.215038 -408.517344 -90)
		(property "Reference" "C709"
			(at 0 0 270)
			(layer "F.SilkS")
			(hide yes)
			(effects
				(font
					(size 1.27 1.27)
				)
			)
		)
		(property "Value" ""
			(at 0 0 270)
			(layer "F.Fab")
			(effects
				(font
					(size 1.27 1.27)
				)
			)
		)
		(duplicate_pad_numbers_are_jumpers no)
		(fp_line
			(start -0.299974 0.150114)
			(end -0.299974 -0.150114)
			(stroke
				(width 0.1)
				(type default)
			)
			(layer "F.Fab")
		)
		(fp_line
			(start 0.299974 0.150114)
			(end -0.299974 0.150114)
			(stroke
				(width 0.1)
				(type default)
			)
			(layer "F.Fab")
		)
		(fp_line
			(start -0.299974 -0.150114)
			(end 0.299974 -0.150114)
			(stroke
				(width 0.1)
				(type default)
			)
			(layer "F.Fab")
		)
		(fp_line
			(start 0.299974 -0.150114)
			(end 0.299974 0.150114)
			(stroke
				(width 0.1)
				(type default)
			)
			(layer "F.Fab")
		)
		(pad "1" smd rect
			(at -0.2667 0 270)
			(size 0.3048 0.381)
			(layers "F.Cu" "F.Mask" "F.Paste")
			(net "P5E_CPU1_PE4_TX_C_DP<0>")
		)
		(pad "2" smd rect
			(at 0.2667 0 270)
			(size 0.3048 0.381)
			(layers "F.Cu" "F.Mask" "F.Paste")
			(net "P5E_CPU1_PE4_TX_DP<0>")
		)
	)
	(footprint ""
		(layer "F.Cu")
		(at 68.093844 -109.483906)
		(property "Reference" "R3731"
			(at 0 0 0)
			(layer "F.SilkS")
			(hide yes)
			(effects
				(font
					(size 1.27 1.27)
				)
			)
		)
		(property "Value" ""
			(at 0 0 0)
			(layer "F.Fab")
			(effects
				(font
					(size 1.27 1.27)
				)
			)
		)
		(duplicate_pad_numbers_are_jumpers no)
		(fp_line
			(start -0.7874 -0.4064)
			(end 0.7874 -0.4064)
			(stroke
				(width 0.1524)
				(type default)
			)
			(layer "F.SilkS")
		)
		(fp_line
			(start -0.7874 0.4064)
			(end -0.7874 -0.4064)
			(stroke
				(width 0.1524)
				(type default)
			)
			(layer "F.SilkS")
		)
		(fp_line
			(start 0.7874 -0.4064)
			(end 0.7874 0.4064)
			(stroke
				(width 0.1524)
				(type default)
			)
			(layer "F.SilkS")
		)
		(fp_line
			(start 0.7874 0.4064)
			(end -0.7874 0.4064)
			(stroke
				(width 0.1524)
				(type default)
			)
			(layer "F.SilkS")
		)
		(fp_line
			(start -0.67945 -0.305054)
			(end -0.12065 -0.305054)
			(stroke
				(width 0.1)
				(type default)
			)
			(layer "F.Fab")
		)
		(fp_line
			(start -0.67945 0.3048)
			(end -0.67945 -0.305054)
			(stroke
				(width 0.1)
				(type default)
			)
			(layer "F.Fab")
		)
		(fp_line
			(start -0.12065 -0.305054)
			(end -0.12065 -0.2794)
			(stroke
				(width 0.1)
				(type default)
			)
			(layer "F.Fab")
		)
		(fp_line
			(start -0.12065 -0.2794)
			(end 0.12065 -0.2794)
			(stroke
				(width 0.1)
				(type default)
			)
			(layer "F.Fab")
		)
		(fp_line
			(start -0.12065 0.2794)
			(end -0.12065 0.3048)
			(stroke
				(width 0.1)
				(type default)
			)
			(layer "F.Fab")
		)
		(fp_line
			(start -0.12065 0.3048)
			(end -0.67945 0.3048)
			(stroke
				(width 0.1)
				(type default)
			)
			(layer "F.Fab")
		)
		(fp_line
			(start 0.120396 0.2794)
			(end -0.12065 0.2794)
			(stroke
				(width 0.1)
				(type default)
			)
			(layer "F.Fab")
		)
		(fp_line
			(start 0.120396 0.3048)
			(end 0.120396 0.2794)
			(stroke
				(width 0.1)
				(type default)
			)
			(layer "F.Fab")
		)
		(fp_line
			(start 0.12065 -0.3048)
			(end 0.67945 -0.3048)
			(stroke
				(width 0.1)
				(type default)
			)
			(layer "F.Fab")
		)
		(fp_line
			(start 0.12065 -0.2794)
			(end 0.12065 -0.3048)
			(stroke
				(width 0.1)
				(type default)
			)
			(layer "F.Fab")
		)
		(fp_line
			(start 0.67945 -0.3048)
			(end 0.67945 0.3048)
			(stroke
				(width 0.1)
				(type default)
			)
			(layer "F.Fab")
		)
		(fp_line
			(start 0.67945 0.3048)
			(end 0.120396 0.3048)
			(stroke
				(width 0.1)
				(type default)
			)
			(layer "F.Fab")
		)
		(pad "1" smd circle
			(at -0.40005 0)
			(size 0 0)
			(layers "F.Cu" "F.Mask" "F.Paste")
			(net "P3V3_AUX")
		)
		(pad "2" smd circle
			(at 0.40005 0)
			(size 0 0)
			(layers "F.Cu" "F.Mask" "F.Paste")
			(net "SMB_LM75_3_3V3AUX_SCL")
		)
	)
)
